# T6G (Grand Teton) — schematic netlist excerpt (pin names and nets, part order shuffled) for the footprints in the layout excerpt that follows; sources: Cadence DE-HDL packaged netlist, KiCad conversion of 04192023_DAF0TMB3IC0_F0TG_MB_C_brd_V02_OCP.brd

PC117_4  Q_CAP  1UF 25V 10% X6S  pkg C0402  page 202 : A = SW_P12V_AUX_PVDDCR_CPU1_P0_FLT ; B = GND
C1822  Q_CAP  0.1UF 25V 10% X7R  pkg 0402  page 139 : A = P3V3_AUX ; B = GND

(kicad_pcb
	(version 20260206)
	(generator "pcbnew")
	(generator_version "10.0")
	(general
		(thickness 1.6)
		(legacy_teardrops no)
	)
	(paper "A4")
	(title_block
		(title "04192023_DAF0TMB3IC0_F0TG_MB_C_brd_V02_OCP.brd")
		(comment 1 "Grand Teton / footprints 4482-4483 of 8354")
	)
	(layers
		(0 "F.Cu" signal "TOP")
		(4 "In1.Cu" signal "GND")
		(6 "In2.Cu" signal "IN1")
		(8 "In3.Cu" signal "GND1")
		(10 "In4.Cu" signal "IN2")
		(12 "In5.Cu" signal "GND2")
		(14 "In6.Cu" signal "IN3")
		(16 "In7.Cu" signal "GND3")
		(18 "In8.Cu" signal "VCC")
		(20 "In9.Cu" signal "VCC1")
		(22 "In10.Cu" signal "GND4")
		(24 "In11.Cu" signal "IN4")
		(26 "In12.Cu" signal "GND5")
		(28 "In13.Cu" signal "IN5")
		(30 "In14.Cu" signal "GND6")
		(32 "In15.Cu" signal "IN6")
		(34 "In16.Cu" signal "GND7")
		(2 "B.Cu" signal "BOTTOM")
		(9 "F.Adhes" user "F.Adhesive")
		(11 "B.Adhes" user "B.Adhesive")
		(13 "F.Paste" user "Package Geometry/Pastemask Top")
		(15 "B.Paste" user "Package Geometry/Pastemask Bottom")
		(5 "F.SilkS" user "Ref Des/Silkscreen Top")
		(7 "B.SilkS" user "Ref Des/Silkscreen Bottom")
		(1 "F.Mask" user "Board Geometry/Soldermask Top")
		(3 "B.Mask" user "Board Geometry/Soldermask Bottom")
		(17 "Dwgs.User" user "User.Drawings")
		(19 "Cmts.User" user "User.Comments")
		(21 "Eco1.User" user "User.Eco1")
		(23 "Eco2.User" user "User.Eco2")
		(25 "Edge.Cuts" user "Board Geometry/Outline")
		(27 "Margin" user)
		(31 "F.CrtYd" user "Package Geometry/Place Bound Top")
		(29 "B.CrtYd" user "Package Geometry/Place Bound Bottom")
		(35 "F.Fab" user "Ref Des/Assembly Top")
		(33 "B.Fab" user "Ref Des/Assembly Bottom")
	)
	(footprint ""
		(layer "F.Cu")
		(at 312.330592 -346.866464 -90)
		(property "Reference" "PC117_4"
			(at 0 0 270)
			(layer "F.SilkS")
			(hide yes)
			(effects
				(font
					(size 1.27 1.27)
				)
			)
		)
		(property "Value" ""
			(at 0 0 270)
			(layer "F.Fab")
			(effects
				(font
					(size 1.27 1.27)
				)
			)
		)
		(duplicate_pad_numbers_are_jumpers no)
		(fp_line
			(start -0.7874 0.4064)
			(end -0.7874 -0.4064)
			(stroke
				(width 0.1524)
				(type default)
			)
			(layer "F.SilkS")
		)
		(fp_line
			(start 0.7874 0.4064)
			(end -0.7874 0.4064)
			(stroke
				(width 0.1524)
				(type default)
			)
			(layer "F.SilkS")
		)
		(fp_line
			(start -0.7874 -0.4064)
			(end 0.7874 -0.4064)
			(stroke
				(width 0.1524)
				(type default)
			)
			(layer "F.SilkS")
		)
		(fp_line
			(start 0.7874 -0.4064)
			(end 0.7874 0.4064)
			(stroke
				(width 0.1524)
				(type default)
			)
			(layer "F.SilkS")
		)
		(fp_line
			(start -0.67945 0.3048)
			(end -0.67945 -0.305054)
			(stroke
				(width 0.1)
				(type default)
			)
			(layer "F.Fab")
		)
		(fp_line
			(start -0.12065 0.3048)
			(end -0.67945 0.3048)
			(stroke
				(width 0.1)
				(type default)
			)
			(layer "F.Fab")
		)
		(fp_line
			(start 0.120396 0.3048)
			(end 0.120396 0.2794)
			(stroke
				(width 0.1)
				(type default)
			)
			(layer "F.Fab")
		)
		(fp_line
			(start 0.67945 0.3048)
			(end 0.120396 0.3048)
			(stroke
				(width 0.1)
				(type default)
			)
			(layer "F.Fab")
		)
		(fp_line
			(start -0.12065 0.2794)
			(end -0.12065 0.3048)
			(stroke
				(width 0.1)
				(type default)
			)
			(layer "F.Fab")
		)
		(fp_line
			(start 0.120396 0.2794)
			(end -0.12065 0.2794)
			(stroke
				(width 0.1)
				(type default)
			)
			(layer "F.Fab")
		)
		(fp_line
			(start -0.12065 -0.2794)
			(end 0.12065 -0.2794)
			(stroke
				(width 0.1)
				(type default)
			)
			(layer "F.Fab")
		)
		(fp_line
			(start 0.12065 -0.2794)
			(end 0.12065 -0.3048)
			(stroke
				(width 0.1)
				(type default)
			)
			(layer "F.Fab")
		)
		(fp_line
			(start 0.12065 -0.3048)
			(end 0.67945 -0.3048)
			(stroke
				(width 0.1)
				(type default)
			)
			(layer "F.Fab")
		)
		(fp_line
			(start 0.67945 -0.3048)
			(end 0.67945 0.3048)
			(stroke
				(width 0.1)
				(type default)
			)
			(layer "F.Fab")
		)
		(fp_line
			(start -0.67945 -0.305054)
			(end -0.12065 -0.305054)
			(stroke
				(width 0.1)
				(type default)
			)
			(layer "F.Fab")
		)
		(fp_line
			(start -0.12065 -0.305054)
			(end -0.12065 -0.2794)
			(stroke
				(width 0.1)
				(type default)
			)
			(layer "F.Fab")
		)
		(pad "1" smd circle
			(at -0.40005 0 270)
			(size 0 0)
			(layers "F.Cu" "F.Mask" "F.Paste")
			(net "SW_P12V_AUX_PVDDCR_CPU1_P0_FLT")
		)
		(pad "2" smd circle
			(at 0.40005 0 270)
			(size 0 0)
			(layers "F.Cu" "F.Mask" "F.Paste")
			(net "GND")
		)
	)
	(footprint ""
		(layer "F.Cu")
		(at 95.88373 -37.865558 180)
		(property "Reference" "C1822"
			(at 0 0 180)
			(layer "F.SilkS")
			(hide yes)
			(effects
				(font
					(size 1.27 1.27)
				)
			)
		)
		(property "Value" ""
			(at 0 0 180)
			(layer "F.Fab")
			(effects
				(font
					(size 1.27 1.27)
				)
			)
		)
		(duplicate_pad_numbers_are_jumpers no)
		(fp_line
			(start 0.7874 0.4064)
			(end -0.7874 0.4064)
			(stroke
				(width 0.1524)
				(type default)
			)
			(layer "F.SilkS")
		)
		(fp_line
			(start 0.7874 -0.4064)
			(end 0.7874 0.4064)
			(stroke
				(width 0.1524)
				(type default)
			)
			(layer "F.SilkS")
		)
		(fp_line
			(start -0.7874 0.4064)
			(end -0.7874 -0.4064)
			(stroke
				(width 0.1524)
				(type default)
			)
			(layer "F.SilkS")
		)
		(fp_line
			(start -0.7874 -0.4064)
			(end 0.7874 -0.4064)
			(stroke
				(width 0.1524)
				(type default)
			)
			(layer "F.SilkS")
		)
		(fp_line
			(start 0.67945 0.3048)
			(end 0.120396 0.3048)
			(stroke
				(width 0.1)
				(type default)
			)
			(layer "F.Fab")
		)
		(fp_line
			(start 0.67945 -0.3048)
			(end 0.67945 0.3048)
			(stroke
				(width 0.1)
				(type default)
			)
			(layer "F.Fab")
		)
		(fp_line
			(start 0.12065 -0.2794)
			(end 0.12065 -0.3048)
			(stroke
				(width 0.1)
				(type default)
			)
			(layer "F.Fab")
		)
		(fp_line
			(start 0.12065 -0.3048)
			(end 0.67945 -0.3048)
			(stroke
				(width 0.1)
				(type default)
			)
			(layer "F.Fab")
		)
		(fp_line
			(start 0.120396 0.3048)
			(end 0.120396 0.2794)
			(stroke
				(width 0.1)
				(type default)
			)
			(layer "F.Fab")
		)
		(fp_line
			(start 0.120396 0.2794)
			(end -0.12065 0.2794)
			(stroke
				(width 0.1)
				(type default)
			)
			(layer "F.Fab")
		)
		(fp_line
			(start -0.12065 0.3048)
			(end -0.67945 0.3048)
			(stroke
				(width 0.1)
				(type default)
			)
			(layer "F.Fab")
		)
		(fp_line
			(start -0.12065 0.2794)
			(end -0.12065 0.3048)
			(stroke
				(width 0.1)
				(type default)
			)
			(layer "F.Fab")
		)
		(fp_line
			(start -0.12065 -0.2794)
			(end 0.12065 -0.2794)
			(stroke
				(width 0.1)
				(type default)
			)
			(layer "F.Fab")
		)
		(fp_line
			(start -0.12065 -0.305054)
			(end -0.12065 -0.2794)
			(stroke
				(width 0.1)
				(type default)
			)
			(layer "F.Fab")
		)
		(fp_line
			(start -0.67945 0.3048)
			(end -0.67945 -0.305054)
			(stroke
				(width 0.1)
				(type default)
			)
			(layer "F.Fab")
		)
		(fp_line
			(start -0.67945 -0.305054)
			(end -0.12065 -0.305054)
			(stroke
				(width 0.1)
				(type default)
			)
			(layer "F.Fab")
		)
		(pad "1" smd circle
			(at -0.40005 0 180)
			(size 0 0)
			(layers "F.Cu" "F.Mask" "F.Paste")
			(net "P3V3_AUX")
		)
		(pad "2" smd circle
			(at 0.40005 0 180)
			(size 0 0)
			(layers "F.Cu" "F.Mask" "F.Paste")
			(net "GND")
		)
	)
)
